(kicad_pcb
	(version 20260206)
	(generator "pcbnew")
	(generator_version "10.0")
	(general
		(thickness 1.6)
		(legacy_teardrops no)
	)
	(paper "A4")
	(title_block
		(title "dpb — 14545-sa.0730WZS0815.brd")
		(comment 1 "Honey Badger (Wiwynn) / footprints 686-692 of 1066")
	)
	(layers
		(0 "F.Cu" signal "TOP")
		(4 "In1.Cu" signal "L2GND")
		(6 "In2.Cu" signal "L3")
		(8 "In3.Cu" signal "L4VCC")
		(10 "In4.Cu" signal "L5VCC")
		(12 "In5.Cu" signal "L6")
		(14 "In6.Cu" signal "L7GND")
		(2 "B.Cu" signal "BOTTOM")
		(9 "F.Adhes" user "F.Adhesive")
		(11 "B.Adhes" user "B.Adhesive")
		(13 "F.Paste" user "Package Geometry/Pastemask Top")
		(15 "B.Paste" user "Package Geometry/Pastemask Bottom")
		(5 "F.SilkS" user "Ref Des/Silkscreen Top")
		(7 "B.SilkS" user "Ref Des/Silkscreen Bottom")
		(1 "F.Mask" user "Board Geometry/Soldermask Top")
		(3 "B.Mask" user "Board Geometry/Soldermask Bottom")
		(17 "Dwgs.User" user "User.Drawings")
		(19 "Cmts.User" user "User.Comments")
		(21 "Eco1.User" user "User.Eco1")
		(23 "Eco2.User" user "User.Eco2")
		(25 "Edge.Cuts" user "Board Geometry/Outline")
		(27 "Margin" user)
		(31 "F.CrtYd" user "Package Geometry/Place Bound Top")
		(29 "B.CrtYd" user "Package Geometry/Place Bound Bottom")
		(35 "F.Fab" user "Ref Des/Assembly Top")
		(33 "B.Fab" user "Ref Des/Assembly Bottom")
	)
	(footprint ""
		(layer "F.Cu")
		(at 62.610746 -391.4267)
		(property "Reference" "C207"
			(at 0 0 0)
			(layer "F.SilkS")
			(hide yes)
			(effects
				(font
					(size 1.27 1.27)
				)
			)
		)
		(property "Value" "SC10U25V6KX-1GP"
			(at -0.0762 -5.1308 0)
			(unlocked yes)
			(layer "F.Fab")
			(hide yes)
			(effects
				(font
					(size 1.016 1.016)
					(thickness 0.1524)
				)
			)
		)
		(property "Device Type" "C1206H71"
			(at -0.127 -6.6548 0)
			(unlocked yes)
			(layer "F.Fab")
			(hide yes)
			(effects
				(font
					(size 1.016 1.016)
					(thickness 0.1524)
				)
			)
		)
		(duplicate_pad_numbers_are_jumpers no)
		(fp_line
			(start -1.016 -2.2352)
			(end 1.016 -2.2352)
			(stroke
				(width 0.1524)
				(type default)
			)
			(layer "F.SilkS")
		)
		(fp_line
			(start -1.016 -0.8382)
			(end -1.016 -2.2352)
			(stroke
				(width 0.1524)
				(type default)
			)
			(layer "F.SilkS")
		)
		(fp_line
			(start -1.016 2.2352)
			(end -1.016 0.8382)
			(stroke
				(width 0.1524)
				(type default)
			)
			(layer "F.SilkS")
		)
		(fp_line
			(start 1.016 -2.2352)
			(end 1.016 -0.8382)
			(stroke
				(width 0.1524)
				(type default)
			)
			(layer "F.SilkS")
		)
		(fp_line
			(start 1.016 0.8382)
			(end 1.016 2.2352)
			(stroke
				(width 0.1524)
				(type default)
			)
			(layer "F.SilkS")
		)
		(fp_line
			(start 1.016 2.2352)
			(end -1.016 2.2352)
			(stroke
				(width 0.1524)
				(type default)
			)
			(layer "F.SilkS")
		)
		(fp_rect
			(start -1.0922 2.3114)
			(end 1.0922 -2.3114)
			(stroke
				(width 0)
				(type default)
			)
			(fill no)
			(layer "F.CrtYd")
		)
		(fp_poly
			(pts
				(xy 1.0922 -2.3114) (xy 1.0922 2.3114) (xy -1.0922 2.3114) (xy -1.0922 -2.3114)
			)
			(stroke
				(width 0)
				(type default)
			)
			(fill no)
			(layer "F.Fab")
		)
		(pad "1" smd rect
			(at 0 -1.397)
			(size 1.651 1.27)
			(layers "F.Cu" "F.Mask" "F.Paste")
			(net "P12V_HDD6")
		)
		(pad "2" smd rect
			(at 0 1.397)
			(size 1.651 1.27)
			(layers "F.Cu" "F.Mask" "F.Paste")
			(net "GND")
		)
	)
	(footprint ""
		(layer "F.Cu")
		(at 200.151746 -82.4357)
		(property "Reference" "U13"
			(at 0 0 0)
			(layer "F.SilkS")
			(hide yes)
			(effects
				(font
					(size 1.27 1.27)
				)
			)
		)
		(property "Value" "74LVC1G08GW-1-GP"
			(at -2.3368 -8.6868 0)
			(unlocked yes)
			(layer "F.Fab")
			(hide yes)
			(effects
				(font
					(size 1.016 1.016)
					(thickness 0.1524)
				)
			)
		)
		(property "Device Type" "SC70-5H44"
			(at -2.3114 -10.414 0)
			(unlocked yes)
			(layer "F.Fab")
			(hide yes)
			(effects
				(font
					(size 1.016 1.016)
					(thickness 0.1524)
				)
			)
		)
		(duplicate_pad_numbers_are_jumpers no)
		(fp_line
			(start -1.27 -1.7018)
			(end 1.27 -1.7018)
			(stroke
				(width 0.1524)
				(type default)
			)
			(layer "F.SilkS")
		)
		(fp_line
			(start -1.27 1.7018)
			(end -1.27 -1.7018)
			(stroke
				(width 0.1524)
				(type default)
			)
			(layer "F.SilkS")
		)
		(fp_line
			(start 0.6604 -1.8034)
			(end 1.3843 -1.8034)
			(stroke
				(width 0.3302)
				(type default)
			)
			(layer "F.SilkS")
		)
		(fp_line
			(start 1.27 -1.7018)
			(end 1.27 1.7018)
			(stroke
				(width 0.1524)
				(type default)
			)
			(layer "F.SilkS")
		)
		(fp_line
			(start 1.27 1.7018)
			(end -1.27 1.7018)
			(stroke
				(width 0.1524)
				(type default)
			)
			(layer "F.SilkS")
		)
		(fp_line
			(start 1.3843 -1.8034)
			(end 1.3843 -1.1176)
			(stroke
				(width 0.3302)
				(type default)
			)
			(layer "F.SilkS")
		)
		(fp_rect
			(start -1.524 1.9558)
			(end 1.524 -1.9558)
			(stroke
				(width 0)
				(type default)
			)
			(fill no)
			(layer "F.CrtYd")
		)
		(fp_poly
			(pts
				(xy -1.524 -1.9558) (xy 1.524 -1.9558) (xy 1.524 1.9558) (xy -1.524 1.9558)
			)
			(stroke
				(width 0)
				(type default)
			)
			(fill no)
			(layer "F.Fab")
		)
		(pad "1" smd rect
			(at 0.65024 -0.8255)
			(size 0.4064 1.2192)
			(layers "F.Cu" "F.Mask" "F.Paste")
			(net "SAS2X28_B_HDD4_FLT")
		)
		(pad "2" smd rect
			(at 0 -0.8255)
			(size 0.4064 1.2192)
			(layers "F.Cu" "F.Mask" "F.Paste")
			(net "SAS2X28_A_HDD4_FLT")
		)
		(pad "3" smd rect
			(at -0.65024 -0.8255)
			(size 0.4064 1.2192)
			(layers "F.Cu" "F.Mask" "F.Paste")
			(net "GND")
		)
		(pad "4" smd rect
			(at -0.65024 0.8255)
			(size 0.4064 1.2192)
			(layers "F.Cu" "F.Mask" "F.Paste")
			(net "FLT_HDD4_DRIVE")
		)
		(pad "5" smd rect
			(at 0.65024 0.8255)
			(size 0.4064 1.2192)
			(layers "F.Cu" "F.Mask" "F.Paste")
			(net "P3V3")
		)
	)
	(footprint ""
		(layer "F.Cu")
		(at 218.646756 -469.928702 -90)
		(property "Reference" "C103"
			(at 0 0 270)
			(layer "F.SilkS")
			(hide yes)
			(effects
				(font
					(size 1.27 1.27)
				)
			)
		)
		(property "Value" "SCD01U50V2KX-1GP"
			(at 1.1811 -2.7051 270)
			(unlocked yes)
			(layer "F.Fab")
			(hide yes)
			(effects
				(font
					(size 1.016 1.016)
					(thickness 0.1524)
				)
			)
		)
		(property "Device Type" "C402H22"
			(at 1.1811 -4.2291 270)
			(unlocked yes)
			(layer "F.Fab")
			(hide yes)
			(effects
				(font
					(size 1.016 1.016)
					(thickness 0.1524)
				)
			)
		)
		(duplicate_pad_numbers_are_jumpers no)
		(fp_rect
			(start -0.4318 0.9525)
			(end 0.4318 -0.9525)
			(stroke
				(width 0)
				(type default)
			)
			(fill no)
			(layer "F.CrtYd")
		)
		(fp_rect
			(start -0.4318 0.9525)
			(end 0.4318 -0.9525)
			(stroke
				(width 0)
				(type default)
			)
			(fill no)
			(layer "F.Fab")
		)
		(pad "1" smd custom
			(at 0 -0.4445 270)
			(size 0.1524 0.1524)
			(layers "F.Cu" "F.Mask" "F.Paste")
			(net "SAS2X28_DRIVE_RX_P_A0")
			(options
				(clearance outline)
				(anchor circle)
			)
			(primitives
				(gr_poly
					(pts
						(arc
							(start 0.3048 -0.2032)
							(mid 0.275042 -0.275042)
							(end 0.2032 -0.3048)
						)
						(arc
							(start -0.2032 -0.3048)
							(mid -0.275042 -0.275042)
							(end -0.3048 -0.2032)
						)
						(arc
							(start -0.3048 0.2032)
							(mid -0.275042 0.275042)
							(end -0.2032 0.3048)
						)
						(arc
							(start 0.2032 0.3048)
							(mid 0.275042 0.275042)
							(end 0.3048 0.2032)
						)
					)
					(width 0)
					(fill yes)
				)
			)
		)
		(pad "2" smd custom
			(at 0 0.4445 270)
			(size 0.1524 0.1524)
			(layers "F.Cu" "F.Mask" "F.Paste")
			(net "SAS2X28_A_HDD0_RX_+")
			(options
				(clearance outline)
				(anchor circle)
			)
			(primitives
				(gr_poly
					(pts
						(arc
							(start 0.3048 -0.2032)
							(mid 0.275042 -0.275042)
							(end 0.2032 -0.3048)
						)
						(arc
							(start -0.2032 -0.3048)
							(mid -0.275042 -0.275042)
							(end -0.3048 -0.2032)
						)
						(arc
							(start -0.3048 0.2032)
							(mid -0.275042 0.275042)
							(end -0.2032 0.3048)
						)
						(arc
							(start 0.2032 0.3048)
							(mid 0.275042 0.275042)
							(end 0.3048 0.2032)
						)
					)
					(width 0)
					(fill yes)
				)
			)
		)
	)
	(footprint ""
		(layer "F.Cu")
		(at 48.9712 -419.8112 180)
		(property "Reference" "R418"
			(at 0 0 180)
			(layer "F.SilkS")
			(hide yes)
			(effects
				(font
					(size 1.27 1.27)
				)
			)
		)
		(property "Value" "0R2J-2-GP"
			(at 0.064008 -3.993896 180)
			(unlocked yes)
			(layer "F.Fab")
			(hide yes)
			(effects
				(font
					(size 1.016 1.016)
					(thickness 0.1524)
				)
			)
		)
		(property "Device Type" "R402H16"
			(at 0.064008 -5.517896 180)
			(unlocked yes)
			(layer "F.Fab")
			(hide yes)
			(effects
				(font
					(size 1.016 1.016)
					(thickness 0.1524)
				)
			)
		)
		(duplicate_pad_numbers_are_jumpers no)
		(fp_line
			(start 0.508 -0.9398)
			(end -0.508 -0.9398)
			(stroke
				(width 0.1524)
				(type default)
			)
			(layer "F.SilkS")
		)
		(fp_line
			(start -0.508 -0.9398)
			(end -0.508 0.9398)
			(stroke
				(width 0.1524)
				(type default)
			)
			(layer "F.SilkS")
		)
		(fp_rect
			(start -0.508 0.9398)
			(end 0.508 -0.9398)
			(stroke
				(width 0)
				(type default)
			)
			(fill no)
			(layer "F.CrtYd")
		)
		(fp_rect
			(start -0.508 0.9398)
			(end 0.508 -0.9398)
			(stroke
				(width 0)
				(type default)
			)
			(fill no)
			(layer "F.Fab")
		)
		(pad "1" smd custom
			(at 0 -0.4445 180)
			(size 0.1397 0.1397)
			(layers "F.Cu" "F.Mask" "F.Paste")
			(net "SW_HDD10_G")
			(options
				(clearance outline)
				(anchor circle)
			)
			(primitives
				(gr_poly
					(pts
						(arc
							(start -0.1778 -0.2794)
							(mid -0.249642 -0.249642)
							(end -0.2794 -0.1778)
						)
						(arc
							(start -0.2794 0.1778)
							(mid -0.249642 0.249642)
							(end -0.1778 0.2794)
						)
						(arc
							(start 0.1778 0.2794)
							(mid 0.249642 0.249642)
							(end 0.2794 0.1778)
						)
						(arc
							(start 0.2794 -0.1778)
							(mid 0.249642 -0.249642)
							(end 0.1778 -0.2794)
						)
					)
					(width 0)
					(fill yes)
				)
			)
		)
		(pad "2" smd custom
			(at 0 0.4445 180)
			(size 0.1397 0.1397)
			(layers "F.Cu" "F.Mask" "F.Paste")
			(net "SW_HDD10_R")
			(options
				(clearance outline)
				(anchor circle)
			)
			(primitives
				(gr_poly
					(pts
						(arc
							(start -0.1778 -0.2794)
							(mid -0.249642 -0.249642)
							(end -0.2794 -0.1778)
						)
						(arc
							(start -0.2794 0.1778)
							(mid -0.249642 0.249642)
							(end -0.1778 0.2794)
						)
						(arc
							(start 0.1778 0.2794)
							(mid 0.249642 0.249642)
							(end 0.2794 0.1778)
						)
						(arc
							(start 0.2794 -0.1778)
							(mid 0.249642 -0.249642)
							(end 0.1778 -0.2794)
						)
					)
					(width 0)
					(fill yes)
				)
			)
		)
	)
	(footprint ""
		(layer "F.Cu")
		(at 94.615 -11.811 -90)
		(property "Reference" "R562"
			(at 0 0 270)
			(layer "F.SilkS")
			(hide yes)
			(effects
				(font
					(size 1.27 1.27)
				)
			)
		)
		(property "Value" "200KR2F-L-GP"
			(at 0.064008 -3.993896 270)
			(unlocked yes)
			(layer "F.Fab")
			(hide yes)
			(effects
				(font
					(size 1.016 1.016)
					(thickness 0.1524)
				)
			)
		)
		(property "Device Type" "R402H16"
			(at 0.064008 -5.517896 270)
			(unlocked yes)
			(layer "F.Fab")
			(hide yes)
			(effects
				(font
					(size 1.016 1.016)
					(thickness 0.1524)
				)
			)
		)
		(duplicate_pad_numbers_are_jumpers no)
		(fp_line
			(start -0.508 -0.9398)
			(end -0.508 0.9398)
			(stroke
				(width 0.1524)
				(type default)
			)
			(layer "F.SilkS")
		)
		(fp_line
			(start 0.508 -0.9398)
			(end -0.508 -0.9398)
			(stroke
				(width 0.1524)
				(type default)
			)
			(layer "F.SilkS")
		)
		(fp_rect
			(start -0.508 0.9398)
			(end 0.508 -0.9398)
			(stroke
				(width 0)
				(type default)
			)
			(fill no)
			(layer "F.CrtYd")
		)
		(fp_rect
			(start -0.508 0.9398)
			(end 0.508 -0.9398)
			(stroke
				(width 0)
				(type default)
			)
			(fill no)
			(layer "F.Fab")
		)
		(pad "1" smd custom
			(at 0 -0.4445 270)
			(size 0.1397 0.1397)
			(layers "F.Cu" "F.Mask" "F.Paste")
			(net "SW_HDD14_R")
			(options
				(clearance outline)
				(anchor circle)
			)
			(primitives
				(gr_poly
					(pts
						(arc
							(start -0.1778 -0.2794)
							(mid -0.249642 -0.249642)
							(end -0.2794 -0.1778)
						)
						(arc
							(start -0.2794 0.1778)
							(mid -0.249642 0.249642)
							(end -0.1778 0.2794)
						)
						(arc
							(start 0.1778 0.2794)
							(mid 0.249642 0.249642)
							(end 0.2794 0.1778)
						)
						(arc
							(start 0.2794 -0.1778)
							(mid 0.249642 -0.249642)
							(end 0.1778 -0.2794)
						)
					)
					(width 0)
					(fill yes)
				)
			)
		)
		(pad "2" smd custom
			(at 0 0.4445 270)
			(size 0.1397 0.1397)
			(layers "F.Cu" "F.Mask" "F.Paste")
			(net "SW_HDD14_N")
			(options
				(clearance outline)
				(anchor circle)
			)
			(primitives
				(gr_poly
					(pts
						(arc
							(start -0.1778 -0.2794)
							(mid -0.249642 -0.249642)
							(end -0.2794 -0.1778)
						)
						(arc
							(start -0.2794 0.1778)
							(mid -0.249642 0.249642)
							(end -0.1778 0.2794)
						)
						(arc
							(start 0.1778 0.2794)
							(mid 0.249642 0.249642)
							(end 0.2794 0.1778)
						)
						(arc
							(start 0.2794 -0.1778)
							(mid 0.249642 -0.249642)
							(end 0.1778 -0.2794)
						)
					)
					(width 0)
					(fill yes)
				)
			)
		)
	)
	(footprint ""
		(layer "F.Cu")
		(at 192.278 -395.351 90)
		(property "Reference" "R120"
			(at 0 0 90)
			(layer "F.SilkS")
			(hide yes)
			(effects
				(font
					(size 1.27 1.27)
				)
			)
		)
		(property "Value" "4K7R2J-2-GP"
			(at 0.064008 -3.993896 90)
			(unlocked yes)
			(layer "F.Fab")
			(hide yes)
			(effects
				(font
					(size 1.016 1.016)
					(thickness 0.1524)
				)
			)
		)
		(property "Device Type" "R402H16"
			(at 0.064008 -5.517896 90)
			(unlocked yes)
			(layer "F.Fab")
			(hide yes)
			(effects
				(font
					(size 1.016 1.016)
					(thickness 0.1524)
				)
			)
		)
		(duplicate_pad_numbers_are_jumpers no)
		(fp_line
			(start 0.508 -0.9398)
			(end -0.508 -0.9398)
			(stroke
				(width 0.1524)
				(type default)
			)
			(layer "F.SilkS")
		)
		(fp_line
			(start -0.508 -0.9398)
			(end -0.508 0.9398)
			(stroke
				(width 0.1524)
				(type default)
			)
			(layer "F.SilkS")
		)
		(fp_rect
			(start -0.508 0.9398)
			(end 0.508 -0.9398)
			(stroke
				(width 0)
				(type default)
			)
			(fill no)
			(layer "F.CrtYd")
		)
		(fp_rect
			(start -0.508 0.9398)
			(end 0.508 -0.9398)
			(stroke
				(width 0)
				(type default)
			)
			(fill no)
			(layer "F.Fab")
		)
		(pad "1" smd custom
			(at 0 -0.4445 90)
			(size 0.1397 0.1397)
			(layers "F.Cu" "F.Mask" "F.Paste")
			(net "P12V")
			(options
				(clearance outline)
				(anchor circle)
			)
			(primitives
				(gr_poly
					(pts
						(arc
							(start -0.1778 -0.2794)
							(mid -0.249642 -0.249642)
							(end -0.2794 -0.1778)
						)
						(arc
							(start -0.2794 0.1778)
							(mid -0.249642 0.249642)
							(end -0.1778 0.2794)
						)
						(arc
							(start 0.1778 0.2794)
							(mid 0.249642 0.249642)
							(end 0.2794 0.1778)
						)
						(arc
							(start 0.2794 -0.1778)
							(mid 0.249642 -0.249642)
							(end 0.1778 -0.2794)
						)
					)
					(width 0)
					(fill yes)
				)
			)
		)
		(pad "2" smd custom
			(at 0 0.4445 90)
			(size 0.1397 0.1397)
			(layers "F.Cu" "F.Mask" "F.Paste")
			(net "SW_HDD1_R")
			(options
				(clearance outline)
				(anchor circle)
			)
			(primitives
				(gr_poly
					(pts
						(arc
							(start -0.1778 -0.2794)
							(mid -0.249642 -0.249642)
							(end -0.2794 -0.1778)
						)
						(arc
							(start -0.2794 0.1778)
							(mid -0.249642 0.249642)
							(end -0.1778 0.2794)
						)
						(arc
							(start 0.1778 0.2794)
							(mid 0.249642 0.249642)
							(end 0.2794 0.1778)
						)
						(arc
							(start 0.2794 -0.1778)
							(mid 0.249642 -0.249642)
							(end 0.1778 -0.2794)
						)
					)
					(width 0)
					(fill yes)
				)
			)
		)
	)
	(footprint ""
		(layer "F.Cu")
		(at 39.750746 -246.7737 90)
		(property "Reference" "R201"
			(at 0 0 90)
			(layer "F.SilkS")
			(hide yes)
			(effects
				(font
					(size 1.27 1.27)
				)
			)
		)
		(property "Value" "330R2F-GP"
			(at 0.064008 -3.993896 90)
			(unlocked yes)
			(layer "F.Fab")
			(hide yes)
			(effects
				(font
					(size 1.016 1.016)
					(thickness 0.1524)
				)
			)
		)
		(property "Device Type" "R402H16"
			(at 0.064008 -5.517896 90)
			(unlocked yes)
			(layer "F.Fab")
			(hide yes)
			(effects
				(font
					(size 1.016 1.016)
					(thickness 0.1524)
				)
			)
		)
		(duplicate_pad_numbers_are_jumpers no)
		(fp_line
			(start 0.508 -0.9398)
			(end -0.508 -0.9398)
			(stroke
				(width 0.1524)
				(type default)
			)
			(layer "F.SilkS")
		)
		(fp_line
			(start -0.508 -0.9398)
			(end -0.508 0.9398)
			(stroke
				(width 0.1524)
				(type default)
			)
			(layer "F.SilkS")
		)
		(fp_rect
			(start -0.508 0.9398)
			(end 0.508 -0.9398)
			(stroke
				(width 0)
				(type default)
			)
			(fill no)
			(layer "F.CrtYd")
		)
		(fp_rect
			(start -0.508 0.9398)
			(end 0.508 -0.9398)
			(stroke
				(width 0)
				(type default)
			)
			(fill no)
			(layer "F.Fab")
		)
		(pad "1" smd custom
			(at 0 -0.4445 90)
			(size 0.1397 0.1397)
			(layers "F.Cu" "F.Mask" "F.Paste")
			(net "P3V3_HDD7_LED")
			(options
				(clearance outline)
				(anchor circle)
			)
			(primitives
				(gr_poly
					(pts
						(arc
							(start -0.1778 -0.2794)
							(mid -0.249642 -0.249642)
							(end -0.2794 -0.1778)
						)
						(arc
							(start -0.2794 0.1778)
							(mid -0.249642 0.249642)
							(end -0.1778 0.2794)
						)
						(arc
							(start 0.1778 0.2794)
							(mid 0.249642 0.249642)
							(end 0.2794 0.1778)
						)
						(arc
							(start 0.2794 -0.1778)
							(mid 0.249642 -0.249642)
							(end 0.1778 -0.2794)
						)
					)
					(width 0)
					(fill yes)
				)
			)
		)
		(pad "2" smd custom
			(at 0 0.4445 90)
			(size 0.1397 0.1397)
			(layers "F.Cu" "F.Mask" "F.Paste")
			(net "FLT_HDD7")
			(options
				(clearance outline)
				(anchor circle)
			)
			(primitives
				(gr_poly
					(pts
						(arc
							(start -0.1778 -0.2794)
							(mid -0.249642 -0.249642)
							(end -0.2794 -0.1778)
						)
						(arc
							(start -0.2794 0.1778)
							(mid -0.249642 0.249642)
							(end -0.1778 0.2794)
						)
						(arc
							(start 0.1778 0.2794)
							(mid 0.249642 0.249642)
							(end 0.2794 0.1778)
						)
						(arc
							(start 0.2794 -0.1778)
							(mid 0.249642 -0.249642)
							(end 0.1778 -0.2794)
						)
					)
					(width 0)
					(fill yes)
				)
			)
		)
	)
)
